(kicad_pcb
	(version 20260206)
	(generator "pcbnew")
	(generator_version "10.0")
	(general
		(thickness 1.6)
		(legacy_teardrops no)
	)
	(paper "A4")
	(title_block
		(title "03242023_DA0F0TMBIJ0_F0T_Motherboard_J_brd_V01_OCP.brd")
		(comment 1 "Grand Teton / footprints 3300-3305 of 6105")
	)
	(layers
		(0 "F.Cu" signal "TOP")
		(4 "In1.Cu" signal "GND")
		(6 "In2.Cu" signal "IN1")
		(8 "In3.Cu" signal "GND1")
		(10 "In4.Cu" signal "IN2")
		(12 "In5.Cu" signal "GND2")
		(14 "In6.Cu" signal "IN3")
		(16 "In7.Cu" signal "GND3")
		(18 "In8.Cu" signal "VCC")
		(20 "In9.Cu" signal "VCC1")
		(22 "In10.Cu" signal "GND4")
		(24 "In11.Cu" signal "IN4")
		(26 "In12.Cu" signal "GND5")
		(28 "In13.Cu" signal "IN5")
		(30 "In14.Cu" signal "GND6")
		(32 "In15.Cu" signal "IN6")
		(34 "In16.Cu" signal "GND7")
		(2 "B.Cu" signal "BOTTOM")
		(9 "F.Adhes" user "F.Adhesive")
		(11 "B.Adhes" user "B.Adhesive")
		(13 "F.Paste" user "Package Geometry/Pastemask Top")
		(15 "B.Paste" user "Package Geometry/Pastemask Bottom")
		(5 "F.SilkS" user "Ref Des/Silkscreen Top")
		(7 "B.SilkS" user "Ref Des/Silkscreen Bottom")
		(1 "F.Mask" user "Board Geometry/Soldermask Top")
		(3 "B.Mask" user "Board Geometry/Soldermask Bottom")
		(17 "Dwgs.User" user "User.Drawings")
		(19 "Cmts.User" user "User.Comments")
		(21 "Eco1.User" user "User.Eco1")
		(23 "Eco2.User" user "User.Eco2")
		(25 "Edge.Cuts" user "Board Geometry/Outline")
		(27 "Margin" user)
		(31 "F.CrtYd" user "Package Geometry/Place Bound Top")
		(29 "B.CrtYd" user "Package Geometry/Place Bound Bottom")
		(35 "F.Fab" user "Ref Des/Assembly Top")
		(33 "B.Fab" user "Ref Des/Assembly Bottom")
	)
	(footprint ""
		(layer "F.Cu")
		(at 74.593958 -61.883798)
		(property "Reference" "PD109"
			(at 5.9944 -0.462788 0)
			(unlocked yes)
			(layer "F.SilkS")
			(effects
				(font
					(size 0.7874 0.5842)
					(thickness 0.1524)
				)
				(justify left)
			)
		)
		(property "Value" ""
			(at 0 0 0)
			(layer "F.Fab")
			(effects
				(font
					(size 1.27 1.27)
				)
			)
		)
		(duplicate_pad_numbers_are_jumpers no)
		(fp_line
			(start -3.400044 -1.459992)
			(end 4.107942 -1.459992)
			(stroke
				(width 0.1524)
				(type default)
			)
			(layer "F.SilkS")
		)
		(fp_line
			(start -3.400044 1.459992)
			(end -3.400044 -1.459992)
			(stroke
				(width 0.1524)
				(type default)
			)
			(layer "F.SilkS")
		)
		(fp_line
			(start 4.107942 -1.459992)
			(end 4.107942 1.459992)
			(stroke
				(width 0.1524)
				(type default)
			)
			(layer "F.SilkS")
		)
		(fp_line
			(start 4.107942 1.459992)
			(end -3.400044 1.459992)
			(stroke
				(width 0.1524)
				(type default)
			)
			(layer "F.SilkS")
		)
		(fp_rect
			(start 3.308096 1.459992)
			(end 4.107942 -1.459992)
			(stroke
				(width 0)
				(type default)
			)
			(fill yes)
			(layer "F.SilkS")
		)
		(fp_line
			(start -2.29997 -1.459992)
			(end 2.29997 -1.459992)
			(stroke
				(width 0.1)
				(type default)
			)
			(layer "F.Fab")
		)
		(fp_line
			(start -2.29997 1.459992)
			(end -2.29997 -1.459992)
			(stroke
				(width 0.1)
				(type default)
			)
			(layer "F.Fab")
		)
		(fp_line
			(start 2.29997 -1.459992)
			(end 2.29997 1.459992)
			(stroke
				(width 0.1)
				(type default)
			)
			(layer "F.Fab")
		)
		(fp_line
			(start 2.29997 1.459992)
			(end -2.29997 1.459992)
			(stroke
				(width 0.1)
				(type default)
			)
			(layer "F.Fab")
		)
		(fp_text user "+"
			(at -4.876038 -1.1557 0)
			(unlocked yes)
			(layer "F.SilkS")
			(effects
				(font
					(size 1.905 1.4224)
					(thickness 0.1524)
				)
				(justify left)
			)
		)
		(fp_text user "-"
			(at 5.4102 0.29845 180)
			(unlocked yes)
			(layer "F.SilkS")
			(effects
				(font
					(size 1.905 1.4224)
					(thickness 0.1524)
				)
				(justify left)
			)
		)
		(fp_text user "+"
			(at -4.7752 -0.12065 0)
			(unlocked yes)
			(layer "F.Fab")
			(effects
				(font
					(size 1.905 1.4224)
					(thickness 0.1524)
				)
				(justify left)
			)
		)
		(fp_text user "-"
			(at 5.4102 0.29845 180)
			(unlocked yes)
			(layer "F.Fab")
			(effects
				(font
					(size 1.905 1.4224)
					(thickness 0.1524)
				)
				(justify left)
			)
		)
		(pad "A" smd rect
			(at -1.999996 0 90)
			(size 1.7018 2.5146)
			(layers "F.Cu" "F.Mask" "F.Paste")
			(net "GND")
		)
		(pad "C" smd rect
			(at 1.999996 0 90)
			(size 1.7018 2.5146)
			(layers "F.Cu" "F.Mask" "F.Paste")
			(net "P3V3_OCP_V3_2_R")
		)
	)
	(footprint ""
		(layer "F.Cu")
		(at 42.324274 -358.38003 90)
		(property "Reference" "PR1803"
			(at 0 0 90)
			(layer "F.SilkS")
			(hide yes)
			(effects
				(font
					(size 1.27 1.27)
				)
			)
		)
		(property "Value" ""
			(at 0 0 90)
			(layer "F.Fab")
			(effects
				(font
					(size 1.27 1.27)
				)
			)
		)
		(duplicate_pad_numbers_are_jumpers no)
		(fp_line
			(start 0.7874 -0.4064)
			(end 0.7874 0.4064)
			(stroke
				(width 0.1524)
				(type default)
			)
			(layer "F.SilkS")
		)
		(fp_line
			(start -0.7874 -0.4064)
			(end 0.7874 -0.4064)
			(stroke
				(width 0.1524)
				(type default)
			)
			(layer "F.SilkS")
		)
		(fp_line
			(start 0.7874 0.4064)
			(end -0.7874 0.4064)
			(stroke
				(width 0.1524)
				(type default)
			)
			(layer "F.SilkS")
		)
		(fp_line
			(start -0.7874 0.4064)
			(end -0.7874 -0.4064)
			(stroke
				(width 0.1524)
				(type default)
			)
			(layer "F.SilkS")
		)
		(fp_line
			(start -0.12065 -0.305054)
			(end -0.12065 -0.2794)
			(stroke
				(width 0.1)
				(type default)
			)
			(layer "F.Fab")
		)
		(fp_line
			(start -0.67945 -0.305054)
			(end -0.12065 -0.305054)
			(stroke
				(width 0.1)
				(type default)
			)
			(layer "F.Fab")
		)
		(fp_line
			(start 0.67945 -0.3048)
			(end 0.67945 0.3048)
			(stroke
				(width 0.1)
				(type default)
			)
			(layer "F.Fab")
		)
		(fp_line
			(start 0.12065 -0.3048)
			(end 0.67945 -0.3048)
			(stroke
				(width 0.1)
				(type default)
			)
			(layer "F.Fab")
		)
		(fp_line
			(start 0.12065 -0.2794)
			(end 0.12065 -0.3048)
			(stroke
				(width 0.1)
				(type default)
			)
			(layer "F.Fab")
		)
		(fp_line
			(start -0.12065 -0.2794)
			(end 0.12065 -0.2794)
			(stroke
				(width 0.1)
				(type default)
			)
			(layer "F.Fab")
		)
		(fp_line
			(start 0.120396 0.2794)
			(end -0.12065 0.2794)
			(stroke
				(width 0.1)
				(type default)
			)
			(layer "F.Fab")
		)
		(fp_line
			(start -0.12065 0.2794)
			(end -0.12065 0.3048)
			(stroke
				(width 0.1)
				(type default)
			)
			(layer "F.Fab")
		)
		(fp_line
			(start 0.67945 0.3048)
			(end 0.120396 0.3048)
			(stroke
				(width 0.1)
				(type default)
			)
			(layer "F.Fab")
		)
		(fp_line
			(start 0.120396 0.3048)
			(end 0.120396 0.2794)
			(stroke
				(width 0.1)
				(type default)
			)
			(layer "F.Fab")
		)
		(fp_line
			(start -0.12065 0.3048)
			(end -0.67945 0.3048)
			(stroke
				(width 0.1)
				(type default)
			)
			(layer "F.Fab")
		)
		(fp_line
			(start -0.67945 0.3048)
			(end -0.67945 -0.305054)
			(stroke
				(width 0.1)
				(type default)
			)
			(layer "F.Fab")
		)
		(pad "1" smd circle
			(at -0.40005 0 90)
			(size 0 0)
			(layers "F.Cu" "F.Mask" "F.Paste")
			(net "SW_PVCCFA_EHV_FIVRA_CPU1_BOOT4")
		)
		(pad "2" smd circle
			(at 0.40005 0 90)
			(size 0 0)
			(layers "F.Cu" "F.Mask" "F.Paste")
			(net "SW_PVCCFA_EHV_FIVRA_CPU1_BOOT4_")
		)
	)
	(footprint ""
		(layer "F.Cu")
		(at 15.436596 -394.231876 180)
		(property "Reference" "R3272"
			(at 0 0 180)
			(layer "F.SilkS")
			(hide yes)
			(effects
				(font
					(size 1.27 1.27)
				)
			)
		)
		(property "Value" ""
			(at 0 0 180)
			(layer "F.Fab")
			(effects
				(font
					(size 1.27 1.27)
				)
			)
		)
		(duplicate_pad_numbers_are_jumpers no)
		(fp_line
			(start 0.7874 0.4064)
			(end -0.7874 0.4064)
			(stroke
				(width 0.1524)
				(type default)
			)
			(layer "F.SilkS")
		)
		(fp_line
			(start 0.7874 -0.4064)
			(end 0.7874 0.4064)
			(stroke
				(width 0.1524)
				(type default)
			)
			(layer "F.SilkS")
		)
		(fp_line
			(start -0.7874 0.4064)
			(end -0.7874 -0.4064)
			(stroke
				(width 0.1524)
				(type default)
			)
			(layer "F.SilkS")
		)
		(fp_line
			(start -0.7874 -0.4064)
			(end 0.7874 -0.4064)
			(stroke
				(width 0.1524)
				(type default)
			)
			(layer "F.SilkS")
		)
		(fp_line
			(start 0.67945 0.3048)
			(end 0.120396 0.3048)
			(stroke
				(width 0.1)
				(type default)
			)
			(layer "F.Fab")
		)
		(fp_line
			(start 0.67945 -0.3048)
			(end 0.67945 0.3048)
			(stroke
				(width 0.1)
				(type default)
			)
			(layer "F.Fab")
		)
		(fp_line
			(start 0.12065 -0.2794)
			(end 0.12065 -0.3048)
			(stroke
				(width 0.1)
				(type default)
			)
			(layer "F.Fab")
		)
		(fp_line
			(start 0.12065 -0.3048)
			(end 0.67945 -0.3048)
			(stroke
				(width 0.1)
				(type default)
			)
			(layer "F.Fab")
		)
		(fp_line
			(start 0.120396 0.3048)
			(end 0.120396 0.2794)
			(stroke
				(width 0.1)
				(type default)
			)
			(layer "F.Fab")
		)
		(fp_line
			(start 0.120396 0.2794)
			(end -0.12065 0.2794)
			(stroke
				(width 0.1)
				(type default)
			)
			(layer "F.Fab")
		)
		(fp_line
			(start -0.12065 0.3048)
			(end -0.67945 0.3048)
			(stroke
				(width 0.1)
				(type default)
			)
			(layer "F.Fab")
		)
		(fp_line
			(start -0.12065 0.2794)
			(end -0.12065 0.3048)
			(stroke
				(width 0.1)
				(type default)
			)
			(layer "F.Fab")
		)
		(fp_line
			(start -0.12065 -0.2794)
			(end 0.12065 -0.2794)
			(stroke
				(width 0.1)
				(type default)
			)
			(layer "F.Fab")
		)
		(fp_line
			(start -0.12065 -0.305054)
			(end -0.12065 -0.2794)
			(stroke
				(width 0.1)
				(type default)
			)
			(layer "F.Fab")
		)
		(fp_line
			(start -0.67945 0.3048)
			(end -0.67945 -0.305054)
			(stroke
				(width 0.1)
				(type default)
			)
			(layer "F.Fab")
		)
		(fp_line
			(start -0.67945 -0.305054)
			(end -0.12065 -0.305054)
			(stroke
				(width 0.1)
				(type default)
			)
			(layer "F.Fab")
		)
		(pad "1" smd circle
			(at -0.40005 0 180)
			(size 0 0)
			(layers "F.Cu" "F.Mask" "F.Paste")
			(net "FM_P2E_EQA1")
		)
		(pad "2" smd circle
			(at 0.40005 0 180)
			(size 0 0)
			(layers "F.Cu" "F.Mask" "F.Paste")
			(net "GND")
		)
	)
	(footprint ""
		(layer "F.Cu")
		(at 106.322114 -258.72694 90)
		(property "Reference" "C226"
			(at 0 0 90)
			(layer "F.SilkS")
			(hide yes)
			(effects
				(font
					(size 1.27 1.27)
				)
			)
		)
		(property "Value" ""
			(at 0 0 90)
			(layer "F.Fab")
			(effects
				(font
					(size 1.27 1.27)
				)
			)
		)
		(duplicate_pad_numbers_are_jumpers no)
		(fp_line
			(start 0.7874 -0.4064)
			(end 0.7874 0.4064)
			(stroke
				(width 0.1524)
				(type default)
			)
			(layer "F.SilkS")
		)
		(fp_line
			(start -0.7874 -0.4064)
			(end 0.7874 -0.4064)
			(stroke
				(width 0.1524)
				(type default)
			)
			(layer "F.SilkS")
		)
		(fp_line
			(start 0.7874 0.4064)
			(end -0.7874 0.4064)
			(stroke
				(width 0.1524)
				(type default)
			)
			(layer "F.SilkS")
		)
		(fp_line
			(start -0.7874 0.4064)
			(end -0.7874 -0.4064)
			(stroke
				(width 0.1524)
				(type default)
			)
			(layer "F.SilkS")
		)
		(fp_line
			(start -0.12065 -0.305054)
			(end -0.12065 -0.2794)
			(stroke
				(width 0.1)
				(type default)
			)
			(layer "F.Fab")
		)
		(fp_line
			(start -0.67945 -0.305054)
			(end -0.12065 -0.305054)
			(stroke
				(width 0.1)
				(type default)
			)
			(layer "F.Fab")
		)
		(fp_line
			(start 0.67945 -0.3048)
			(end 0.67945 0.3048)
			(stroke
				(width 0.1)
				(type default)
			)
			(layer "F.Fab")
		)
		(fp_line
			(start 0.12065 -0.3048)
			(end 0.67945 -0.3048)
			(stroke
				(width 0.1)
				(type default)
			)
			(layer "F.Fab")
		)
		(fp_line
			(start 0.12065 -0.2794)
			(end 0.12065 -0.3048)
			(stroke
				(width 0.1)
				(type default)
			)
			(layer "F.Fab")
		)
		(fp_line
			(start -0.12065 -0.2794)
			(end 0.12065 -0.2794)
			(stroke
				(width 0.1)
				(type default)
			)
			(layer "F.Fab")
		)
		(fp_line
			(start 0.120396 0.2794)
			(end -0.12065 0.2794)
			(stroke
				(width 0.1)
				(type default)
			)
			(layer "F.Fab")
		)
		(fp_line
			(start -0.12065 0.2794)
			(end -0.12065 0.3048)
			(stroke
				(width 0.1)
				(type default)
			)
			(layer "F.Fab")
		)
		(fp_line
			(start 0.67945 0.3048)
			(end 0.120396 0.3048)
			(stroke
				(width 0.1)
				(type default)
			)
			(layer "F.Fab")
		)
		(fp_line
			(start 0.120396 0.3048)
			(end 0.120396 0.2794)
			(stroke
				(width 0.1)
				(type default)
			)
			(layer "F.Fab")
		)
		(fp_line
			(start -0.12065 0.3048)
			(end -0.67945 0.3048)
			(stroke
				(width 0.1)
				(type default)
			)
			(layer "F.Fab")
		)
		(fp_line
			(start -0.67945 0.3048)
			(end -0.67945 -0.305054)
			(stroke
				(width 0.1)
				(type default)
			)
			(layer "F.Fab")
		)
		(pad "1" smd circle
			(at -0.40005 0 90)
			(size 0 0)
			(layers "F.Cu" "F.Mask" "F.Paste")
			(net "PVCCIN_CPU1")
		)
		(pad "2" smd circle
			(at 0.40005 0 90)
			(size 0 0)
			(layers "F.Cu" "F.Mask" "F.Paste")
			(net "GND")
		)
	)
	(footprint ""
		(layer "F.Cu")
		(at 40.627554 -112.603026)
		(property "Reference" "R3679"
			(at 0 0 0)
			(layer "F.SilkS")
			(hide yes)
			(effects
				(font
					(size 1.27 1.27)
				)
			)
		)
		(property "Value" ""
			(at 0 0 0)
			(layer "F.Fab")
			(effects
				(font
					(size 1.27 1.27)
				)
			)
		)
		(duplicate_pad_numbers_are_jumpers no)
		(fp_line
			(start -0.7874 -0.4064)
			(end 0.7874 -0.4064)
			(stroke
				(width 0.1524)
				(type default)
			)
			(layer "F.SilkS")
		)
		(fp_line
			(start -0.7874 0.4064)
			(end -0.7874 -0.4064)
			(stroke
				(width 0.1524)
				(type default)
			)
			(layer "F.SilkS")
		)
		(fp_line
			(start 0.7874 -0.4064)
			(end 0.7874 0.4064)
			(stroke
				(width 0.1524)
				(type default)
			)
			(layer "F.SilkS")
		)
		(fp_line
			(start 0.7874 0.4064)
			(end -0.7874 0.4064)
			(stroke
				(width 0.1524)
				(type default)
			)
			(layer "F.SilkS")
		)
		(fp_line
			(start -0.67945 -0.305054)
			(end -0.12065 -0.305054)
			(stroke
				(width 0.1)
				(type default)
			)
			(layer "F.Fab")
		)
		(fp_line
			(start -0.67945 0.3048)
			(end -0.67945 -0.305054)
			(stroke
				(width 0.1)
				(type default)
			)
			(layer "F.Fab")
		)
		(fp_line
			(start -0.12065 -0.305054)
			(end -0.12065 -0.2794)
			(stroke
				(width 0.1)
				(type default)
			)
			(layer "F.Fab")
		)
		(fp_line
			(start -0.12065 -0.2794)
			(end 0.12065 -0.2794)
			(stroke
				(width 0.1)
				(type default)
			)
			(layer "F.Fab")
		)
		(fp_line
			(start -0.12065 0.2794)
			(end -0.12065 0.3048)
			(stroke
				(width 0.1)
				(type default)
			)
			(layer "F.Fab")
		)
		(fp_line
			(start -0.12065 0.3048)
			(end -0.67945 0.3048)
			(stroke
				(width 0.1)
				(type default)
			)
			(layer "F.Fab")
		)
		(fp_line
			(start 0.120396 0.2794)
			(end -0.12065 0.2794)
			(stroke
				(width 0.1)
				(type default)
			)
			(layer "F.Fab")
		)
		(fp_line
			(start 0.120396 0.3048)
			(end 0.120396 0.2794)
			(stroke
				(width 0.1)
				(type default)
			)
			(layer "F.Fab")
		)
		(fp_line
			(start 0.12065 -0.3048)
			(end 0.67945 -0.3048)
			(stroke
				(width 0.1)
				(type default)
			)
			(layer "F.Fab")
		)
		(fp_line
			(start 0.12065 -0.2794)
			(end 0.12065 -0.3048)
			(stroke
				(width 0.1)
				(type default)
			)
			(layer "F.Fab")
		)
		(fp_line
			(start 0.67945 -0.3048)
			(end 0.67945 0.3048)
			(stroke
				(width 0.1)
				(type default)
			)
			(layer "F.Fab")
		)
		(fp_line
			(start 0.67945 0.3048)
			(end 0.120396 0.3048)
			(stroke
				(width 0.1)
				(type default)
			)
			(layer "F.Fab")
		)
		(pad "1" smd rect
			(at -0.40005 0 180)
			(size 0.4572 0.508)
			(layers "F.Cu" "F.Mask" "F.Paste")
			(net "P12V_AUX_ADC")
		)
		(pad "2" smd rect
			(at 0.40005 0 180)
			(size 0.4572 0.508)
			(layers "F.Cu" "F.Mask" "F.Paste")
			(net "P12V_AUX_ADC_MAM")
		)
	)
	(footprint ""
		(layer "F.Cu")
		(at 266.031472 -398.78 90)
		(property "Reference" "PPQ7"
			(at -8.177784 -1.879092 0)
			(unlocked yes)
			(layer "F.SilkS")
			(effects
				(font
					(size 0.7874 0.5842)
					(thickness 0.1524)
				)
				(justify left)
			)
		)
		(property "Value" ""
			(at 0 0 90)
			(layer "F.Fab")
			(effects
				(font
					(size 1.27 1.27)
				)
			)
		)
		(duplicate_pad_numbers_are_jumpers no)
		(fp_line
			(start 2.350008 -2.649982)
			(end 2.350008 -2.4892)
			(stroke
				(width 0.1524)
				(type default)
			)
			(layer "F.SilkS")
		)
		(fp_line
			(start -2.350008 -2.649982)
			(end 2.350008 -2.649982)
			(stroke
				(width 0.1524)
				(type default)
			)
			(layer "F.SilkS")
		)
		(fp_line
			(start -2.350008 -2.4384)
			(end -2.350008 -2.649982)
			(stroke
				(width 0.1524)
				(type default)
			)
			(layer "F.SilkS")
		)
		(fp_line
			(start 2.350008 2.4892)
			(end 2.350008 2.649982)
			(stroke
				(width 0.1524)
				(type default)
			)
			(layer "F.SilkS")
		)
		(fp_line
			(start 2.350008 2.649982)
			(end -2.350008 2.649982)
			(stroke
				(width 0.1524)
				(type default)
			)
			(layer "F.SilkS")
		)
		(fp_line
			(start -2.350008 2.649982)
			(end -2.350008 2.413)
			(stroke
				(width 0.1524)
				(type default)
			)
			(layer "F.SilkS")
		)
		(fp_poly
			(pts
				(xy -3.717544 -1.905) (xy -4.758944 -2.3241) (xy -4.758944 -1.524)
			)
			(stroke
				(width 0)
				(type default)
			)
			(fill yes)
			(layer "F.SilkS")
		)
		(fp_line
			(start 2.350008 -2.649982)
			(end 2.350008 2.649982)
			(stroke
				(width 0.1)
				(type default)
			)
			(layer "F.Fab")
		)
		(fp_line
			(start -2.350008 -2.649982)
			(end 2.350008 -2.649982)
			(stroke
				(width 0.1)
				(type default)
			)
			(layer "F.Fab")
		)
		(fp_line
			(start 2.350008 2.649982)
			(end -2.350008 2.649982)
			(stroke
				(width 0.1)
				(type default)
			)
			(layer "F.Fab")
		)
		(fp_line
			(start -2.350008 2.649982)
			(end -2.350008 -2.649982)
			(stroke
				(width 0.1)
				(type default)
			)
			(layer "F.Fab")
		)
		(fp_poly
			(pts
				(xy -3.717544 -1.905) (xy -4.758944 -2.3241) (xy -4.758944 -1.524)
			)
			(stroke
				(width 0)
				(type default)
			)
			(fill yes)
			(layer "F.Fab")
		)
		(pad "1" smd rect
			(at -2.999994 -1.905)
			(size 0.7112 1.1684)
			(layers "F.Cu" "F.Mask" "F.Paste")
			(net "P12V_AUX")
		)
		(pad "2" smd rect
			(at -2.999994 -0.635)
			(size 0.7112 1.1684)
			(layers "F.Cu" "F.Mask" "F.Paste")
			(net "P12V_AUX")
		)
		(pad "3" smd rect
			(at -2.999994 0.635)
			(size 0.7112 1.1684)
			(layers "F.Cu" "F.Mask" "F.Paste")
			(net "P12V_AUX")
		)
		(pad "4" smd rect
			(at -2.999994 1.905)
			(size 0.7112 1.1684)
			(layers "F.Cu" "F.Mask" "F.Paste")
			(net "P12V_HSC_GATE_G3")
		)
		(pad "5" smd circle
			(at 0.925068 0)
			(size 0 0)
			(layers "F.Cu" "F.Mask" "F.Paste")
			(net "P12V_MAIN_R")
		)
		(zone
			(layer "F.Cu")
			(hatch none 0.5)
			(connect_pads
				(clearance 0)
			)
			(min_thickness 0.25)
			(keepout
				(tracks not_allowed)
				(vias allowed)
				(pads allowed)
				(copperpour not_allowed)
				(footprints allowed)
			)
			(placement
				(enabled no)
				(sheetname "")
			)
			(fill
				(thermal_gap 0.5)
				(thermal_bridge_width 0.5)
				(island_removal_mode 0)
			)
			(polygon
				(pts
					(xy 263.872472 -397.3322) (xy 268.190472 -397.3322) (xy 268.673072 -397.3322) (xy 268.673072 -396.4305)
					(xy 263.389872 -396.4305) (xy 263.389872 -397.3322)
				)
			)
		)
	)
)
